# T6G (Grand Teton) — schematic netlist excerpt (pin names and nets, part order shuffled) for the footprints in the layout excerpt that follows; sources: Cadence DE-HDL packaged netlist, KiCad conversion of 04192023_DAF0TMB3IC0_F0TG_MB_C_brd_V02_OCP.brd

R2417  Q_RES  33.2 1% CHIP  pkg 0402LF  page 150 : A = SMB_HOST_CLK_3V3AUX_SCL ; B = SMB_HOST_CLK_3V3AUX_SCL_R0
C2490  Q_CAP  22UF 4V 20% X6S  pkg C0402  page 74 : A = PVDD11_S3_P1 ; B = GND
C1000  Q_CAP  1UF 4V 20% X6S  pkg 0201  page 312 : A = P1V8_CPU0_RT3_1A ; B = GND

(kicad_pcb
	(version 20260206)
	(generator "pcbnew")
	(generator_version "10.0")
	(general
		(thickness 1.6)
		(legacy_teardrops no)
	)
	(paper "A4")
	(title_block
		(title "04192023_DAF0TMB3IC0_F0TG_MB_C_brd_V02_OCP.brd")
		(comment 1 "Grand Teton / footprints 7610-7612 of 8354")
	)
	(layers
		(0 "F.Cu" signal "TOP")
		(4 "In1.Cu" signal "GND")
		(6 "In2.Cu" signal "IN1")
		(8 "In3.Cu" signal "GND1")
		(10 "In4.Cu" signal "IN2")
		(12 "In5.Cu" signal "GND2")
		(14 "In6.Cu" signal "IN3")
		(16 "In7.Cu" signal "GND3")
		(18 "In8.Cu" signal "VCC")
		(20 "In9.Cu" signal "VCC1")
		(22 "In10.Cu" signal "GND4")
		(24 "In11.Cu" signal "IN4")
		(26 "In12.Cu" signal "GND5")
		(28 "In13.Cu" signal "IN5")
		(30 "In14.Cu" signal "GND6")
		(32 "In15.Cu" signal "IN6")
		(34 "In16.Cu" signal "GND7")
		(2 "B.Cu" signal "BOTTOM")
		(9 "F.Adhes" user "F.Adhesive")
		(11 "B.Adhes" user "B.Adhesive")
		(13 "F.Paste" user "Package Geometry/Pastemask Top")
		(15 "B.Paste" user "Package Geometry/Pastemask Bottom")
		(5 "F.SilkS" user "Ref Des/Silkscreen Top")
		(7 "B.SilkS" user "Ref Des/Silkscreen Bottom")
		(1 "F.Mask" user "Board Geometry/Soldermask Top")
		(3 "B.Mask" user "Board Geometry/Soldermask Bottom")
		(17 "Dwgs.User" user "User.Drawings")
		(19 "Cmts.User" user "User.Comments")
		(21 "Eco1.User" user "User.Eco1")
		(23 "Eco2.User" user "User.Eco2")
		(25 "Edge.Cuts" user "Board Geometry/Outline")
		(27 "Margin" user)
		(31 "F.CrtYd" user "Package Geometry/Place Bound Top")
		(29 "B.CrtYd" user "Package Geometry/Place Bound Bottom")
		(35 "F.Fab" user "Ref Des/Assembly Top")
		(33 "B.Fab" user "Ref Des/Assembly Bottom")
	)
	(footprint ""
		(layer "B.Cu")
		(at 104.561386 -264.354564)
		(property "Reference" "C2490"
			(at 0 0 0)
			(layer "B.SilkS")
			(hide yes)
			(effects
				(font
					(size 1.27 1.27)
				)
				(justify mirror)
			)
		)
		(property "Value" ""
			(at 0 0 0)
			(layer "B.Fab")
			(effects
				(font
					(size 1.27 1.27)
				)
				(justify mirror)
			)
		)
		(duplicate_pad_numbers_are_jumpers no)
		(fp_line
			(start -0.7874 -0.4064)
			(end -0.7874 0.4064)
			(stroke
				(width 0.1524)
				(type default)
			)
			(layer "B.SilkS")
		)
		(fp_line
			(start -0.7874 0.4064)
			(end 0.7874 0.4064)
			(stroke
				(width 0.1524)
				(type default)
			)
			(layer "B.SilkS")
		)
		(fp_line
			(start 0.7874 -0.4064)
			(end -0.7874 -0.4064)
			(stroke
				(width 0.1524)
				(type default)
			)
			(layer "B.SilkS")
		)
		(fp_line
			(start 0.7874 0.4064)
			(end 0.7874 -0.4064)
			(stroke
				(width 0.1524)
				(type default)
			)
			(layer "B.SilkS")
		)
		(fp_line
			(start -0.67945 -0.3048)
			(end -0.67945 0.3048)
			(stroke
				(width 0.1)
				(type default)
			)
			(layer "B.Fab")
		)
		(fp_line
			(start -0.67945 0.3048)
			(end -0.120396 0.3048)
			(stroke
				(width 0.1)
				(type default)
			)
			(layer "B.Fab")
		)
		(fp_line
			(start -0.12065 -0.3048)
			(end -0.67945 -0.3048)
			(stroke
				(width 0.1)
				(type default)
			)
			(layer "B.Fab")
		)
		(fp_line
			(start -0.12065 -0.2794)
			(end -0.12065 -0.3048)
			(stroke
				(width 0.1)
				(type default)
			)
			(layer "B.Fab")
		)
		(fp_line
			(start -0.120396 0.2794)
			(end 0.12065 0.2794)
			(stroke
				(width 0.1)
				(type default)
			)
			(layer "B.Fab")
		)
		(fp_line
			(start -0.120396 0.3048)
			(end -0.120396 0.2794)
			(stroke
				(width 0.1)
				(type default)
			)
			(layer "B.Fab")
		)
		(fp_line
			(start 0.12065 -0.305054)
			(end 0.12065 -0.2794)
			(stroke
				(width 0.1)
				(type default)
			)
			(layer "B.Fab")
		)
		(fp_line
			(start 0.12065 -0.2794)
			(end -0.12065 -0.2794)
			(stroke
				(width 0.1)
				(type default)
			)
			(layer "B.Fab")
		)
		(fp_line
			(start 0.12065 0.2794)
			(end 0.12065 0.3048)
			(stroke
				(width 0.1)
				(type default)
			)
			(layer "B.Fab")
		)
		(fp_line
			(start 0.12065 0.3048)
			(end 0.67945 0.3048)
			(stroke
				(width 0.1)
				(type default)
			)
			(layer "B.Fab")
		)
		(fp_line
			(start 0.67945 -0.305054)
			(end 0.12065 -0.305054)
			(stroke
				(width 0.1)
				(type default)
			)
			(layer "B.Fab")
		)
		(fp_line
			(start 0.67945 0.3048)
			(end 0.67945 -0.305054)
			(stroke
				(width 0.1)
				(type default)
			)
			(layer "B.Fab")
		)
		(pad "1" smd circle
			(at 0.40005 0 180)
			(size 0 0)
			(layers "B.Cu" "B.Mask" "B.Paste")
			(net "PVDD11_S3_P1")
		)
		(pad "2" smd circle
			(at -0.40005 0 180)
			(size 0 0)
			(layers "B.Cu" "B.Mask" "B.Paste")
			(net "GND")
		)
	)
	(footprint ""
		(layer "B.Cu")
		(at 377.818396 -396.393162 -90)
		(property "Reference" "C1000"
			(at 0 0 90)
			(layer "B.SilkS")
			(hide yes)
			(effects
				(font
					(size 1.27 1.27)
				)
				(justify mirror)
			)
		)
		(property "Value" ""
			(at 0 0 90)
			(layer "B.Fab")
			(effects
				(font
					(size 1.27 1.27)
				)
				(justify mirror)
			)
		)
		(duplicate_pad_numbers_are_jumpers no)
		(fp_line
			(start -0.299974 0.150114)
			(end 0.299974 0.150114)
			(stroke
				(width 0.1)
				(type default)
			)
			(layer "B.Fab")
		)
		(fp_line
			(start 0.299974 0.150114)
			(end 0.299974 -0.150114)
			(stroke
				(width 0.1)
				(type default)
			)
			(layer "B.Fab")
		)
		(fp_line
			(start -0.299974 -0.150114)
			(end -0.299974 0.150114)
			(stroke
				(width 0.1)
				(type default)
			)
			(layer "B.Fab")
		)
		(fp_line
			(start 0.299974 -0.150114)
			(end -0.299974 -0.150114)
			(stroke
				(width 0.1)
				(type default)
			)
			(layer "B.Fab")
		)
		(pad "1" smd rect
			(at 0.2667 0 90)
			(size 0.3048 0.381)
			(layers "B.Cu" "B.Mask" "B.Paste")
			(net "P1V8_CPU0_RT3_1A")
		)
		(pad "2" smd rect
			(at -0.2667 0 90)
			(size 0.3048 0.381)
			(layers "B.Cu" "B.Mask" "B.Paste")
			(net "GND")
		)
	)
	(footprint ""
		(layer "B.Cu")
		(at 150.97887 -13.762228 90)
		(property "Reference" "R2417"
			(at 0 0 90)
			(layer "B.SilkS")
			(hide yes)
			(effects
				(font
					(size 1.27 1.27)
				)
				(justify mirror)
			)
		)
		(property "Value" ""
			(at 0 0 90)
			(layer "B.Fab")
			(effects
				(font
					(size 1.27 1.27)
				)
				(justify mirror)
			)
		)
		(duplicate_pad_numbers_are_jumpers no)
		(fp_line
			(start 0.7874 -0.4064)
			(end -0.7874 -0.4064)
			(stroke
				(width 0.1524)
				(type default)
			)
			(layer "B.SilkS")
		)
		(fp_line
			(start -0.7874 -0.4064)
			(end -0.7874 0.4064)
			(stroke
				(width 0.1524)
				(type default)
			)
			(layer "B.SilkS")
		)
		(fp_line
			(start 0.7874 0.4064)
			(end 0.7874 -0.4064)
			(stroke
				(width 0.1524)
				(type default)
			)
			(layer "B.SilkS")
		)
		(fp_line
			(start -0.7874 0.4064)
			(end 0.7874 0.4064)
			(stroke
				(width 0.1524)
				(type default)
			)
			(layer "B.SilkS")
		)
		(fp_line
			(start 0.67945 -0.305054)
			(end 0.12065 -0.305054)
			(stroke
				(width 0.1)
				(type default)
			)
			(layer "B.Fab")
		)
		(fp_line
			(start 0.12065 -0.305054)
			(end 0.12065 -0.2794)
			(stroke
				(width 0.1)
				(type default)
			)
			(layer "B.Fab")
		)
		(fp_line
			(start -0.12065 -0.3048)
			(end -0.67945 -0.3048)
			(stroke
				(width 0.1)
				(type default)
			)
			(layer "B.Fab")
		)
		(fp_line
			(start -0.67945 -0.3048)
			(end -0.67945 0.3048)
			(stroke
				(width 0.1)
				(type default)
			)
			(layer "B.Fab")
		)
		(fp_line
			(start 0.12065 -0.2794)
			(end -0.12065 -0.2794)
			(stroke
				(width 0.1)
				(type default)
			)
			(layer "B.Fab")
		)
		(fp_line
			(start -0.12065 -0.2794)
			(end -0.12065 -0.3048)
			(stroke
				(width 0.1)
				(type default)
			)
			(layer "B.Fab")
		)
		(fp_line
			(start 0.12065 0.2794)
			(end 0.12065 0.3048)
			(stroke
				(width 0.1)
				(type default)
			)
			(layer "B.Fab")
		)
		(fp_line
			(start -0.120396 0.2794)
			(end 0.12065 0.2794)
			(stroke
				(width 0.1)
				(type default)
			)
			(layer "B.Fab")
		)
		(fp_line
			(start 0.67945 0.3048)
			(end 0.67945 -0.305054)
			(stroke
				(width 0.1)
				(type default)
			)
			(layer "B.Fab")
		)
		(fp_line
			(start 0.12065 0.3048)
			(end 0.67945 0.3048)
			(stroke
				(width 0.1)
				(type default)
			)
			(layer "B.Fab")
		)
		(fp_line
			(start -0.120396 0.3048)
			(end -0.120396 0.2794)
			(stroke
				(width 0.1)
				(type default)
			)
			(layer "B.Fab")
		)
		(fp_line
			(start -0.67945 0.3048)
			(end -0.120396 0.3048)
			(stroke
				(width 0.1)
				(type default)
			)
			(layer "B.Fab")
		)
		(pad "1" smd circle
			(at 0.40005 0 270)
			(size 0 0)
			(layers "B.Cu" "B.Mask" "B.Paste")
			(net "SMB_HOST_CLK_3V3AUX_SCL")
		)
		(pad "2" smd circle
			(at -0.40005 0 270)
			(size 0 0)
			(layers "B.Cu" "B.Mask" "B.Paste")
			(net "SMB_HOST_CLK_3V3AUX_SCL_R0")
		)
	)
)
